FILE_TYPE = CONNECTIVITY;
{Allegro Design Entry HDL 17.4-2019 S026 (4007227) 1/17/2022}
"PAGE_NUMBER" = 153;
0"NC";
1"P3V3_AUX\g";
2"P5V_AUX\g";
3"P5V_AUX\g";
4"GND\g";
5"GND\g";
6"GND\g";
7"GND\g";
8"GND\g";
9"GND\g";
10"PU_CPU0_USB_HUB_RESERVED2";
11"SMB_USB_CPU0_HUB1_SDA";
12"XTAL_USB_CPU0_HUB1_XIN";
13"GND\g";
14"RST_USB_CPU0_HUB1_R_N";
15"USB_CPU0_HUB1_MODE_SEL0";
16"GND\g";
17"P3V3_AUX\g";
18"P3V3_AUX\g";
19"P3V3_AUX\g";
20"GND\g";
21"P3V3_AUX\g";
22"GND\g";
23"P5V_AUX\g";
24"GND\g";
25"GND\g";
26"GND\g";
27"USB_CPU0_HUB1_MODE_SEL1";
28"USB2_CPU0_P0_HUB1_R_DN";
29"USB2_CPU0_P0_HUB1_R_DP";
30"USB3_CPU0_BMC_RX_C1_DN";
31"USB3_CPU0_BMC_RX_C1_DP";
32"SMB_USB_CPU0_HUB1_SDA_R2";
33"SMB_USB_CPU0_HUB1_SCL_R2";
34"PD_USB_CPU0_WP";
35"USB_CPU0_ADD_A2";
36"USB_CPU0_ADD_A1";
37"USB_CPU0_ADD_A0";
38"SMB_USB_CPU0_HUB1_SCL";
39"PU_CPU0_USB_HUB_PWR_EN";
40"PU_CPU0_USB_HUB_OVRCURR";
41"PU_CPU0_USB_HUB_RESERVED1";
42"SMB_USB_CPU0_HUB1_SCL";
43"USB3_CPU0_BMC_HUB1_TX_DP";
44"USB_CPU0_HUB1_VBUS_DS";
45"XTAL_USB_CPU0_HUB1_XOUT";
46"USB_CPU0_HUB1_RREF_USB2";
47"USB_CPU0_HUB1_RREF_SS";
48"SMB_USB_CPU0_HUB1_SDA";
49"USB3_CPU0_BMC_RX_HUB1_DP";
50"RST_USB_HUB_N";
51"TP_CPU0_USB_HUB1_SUSPEND";
52"USB3_CPU0_BMC_TX_C1_DP";
53"USB3_CPU0_BMC_TX_C1_DN";
54"USB3_CPU0_BMC_RX_HUB1_DN";
55"USB2_CPU0_P0_R1_DP";
56"USB2_CPU0_P0_R1_DN";
57"USB_CPU0_HUB1_VBUS_US";
58"USB3_CPU0_BMC_HUB1_TX_DN";
%"CYUSB330468LTXI"
"1","(-4650,3650)","0","pure_quanta","I1";
;
LOCATION"U6001"
SEC"1"
PART_TYPE"SMLF"
MATERIAL"IC"
ROOM"USB3_HUB1_CYP"
VALUE"CYUSB3304-68LTXI"
SEC_TYPE""
CDS_LIB"pure_quanta"
CDS_LMAN_SYM_OUTLINE"-475,2575,475,-2575"
NEEDS_NO_SIZE"TRUE"
PART_NUMBER"AJ033040001";
"EPAD"
$PN"TH"16;
"RESERVED1"
$PN"21"41;
"RESERVED2"
$PN"22"10;
"RESET# \B"
$PN"31"14;
"OVRCURR"
$PN"30"40;
"PWR_EN"
$PN"29"39;
"NC_25"
$PN"25"0;
"RREF_USB2"
$PN"2"46;
"RREF_SS"
$PN"26"47;
"US_TXM"
$PN"5"54;
"US_TXP"
$PN"6"49;
"US_RXM"
$PN"8"53;
"US_RXP"
$PN"9"52;
"US_DM"
$PN"58"56;
"US_DP"
$PN"57"55;
"VBUS_US"
$PN"17"57;
"GND"
$PN"40"16;
"MODE_SEL1"
$PN"24"27;
"MODE_SEL0"
$PN"23"15;
"XTL_OUT"
$PN"54"45;
"XTL_IN"
$PN"55"12;
"SUSPEND"
$PN"20"51;
"I2C_DATA"
$PN"33"48;
"I2C_CLK"
$PN"32"42;
"VBUS_DS"
$PN"18"44;
"DS4_TXM"
$PN"12"0;
"DS4_TXP"
$PN"11"0;
"DS4_RXM"
$PN"14"0;
"DS4_RXP"
$PN"15"0;
"DS4_DM"
$PN"68"0;
"DS4_DP"
$PN"67"0;
"DS3_TXM"
$PN"39"0;
"DS3_TXP"
$PN"38"0;
"DS3_RXM"
$PN"36"0;
"DS3_RXP"
$PN"35"0;
"DS3_DM"
$PN"64"0;
"DS3_DP"
$PN"65"0;
"DS2_TXM"
$PN"42"0;
"DS2_TXP"
$PN"41"0;
"DS2_RXM"
$PN"44"0;
"DS2_RXP"
$PN"45"0;
"DS2_DM"
$PN"63"0;
"DS2_DP"
$PN"62"0;
"DS1_TXM"
$PN"48"58;
"DS1_TXP"
$PN"47"43;
"DS1_RXM"
$PN"50"30;
"DS1_RXP"
$PN"51"31;
"DS1_DM"
$PN"59"28;
"DS1_DP"
$PN"60"29;
%"Q_XTAL_4P_13BI_24GND"
"1","(-7000,1675)","2","pure_quanta","I14";
;
LOCATION"Y9"
SEC"1"
PART_TYPE"SMLF"
ROOM"USB3_HUB1_CYP"
VALUE"26MHZ"
MATERIAL"MISC"
SEC_TYPE""
CDS_LMAN_SYM_OUTLINE"-125,175,125,-175"
PIN_NAMES_ROTATE"True"
CDS_LIB"pure_quanta"
PART_NUMBER"BG626000049";
"X2"
$PN"3"45;
"G2"
$PN"4"26;
"G1"
$PN"2"13;
"X1"
$PN"1"12;
%"GND"
"1","(-8000,1025)","0","pure_quanta_power","I15";
;
CDS_LIB"pure_quanta_power"
SIZE"1B"
HDL_POWER"GND";
"A<SIZE-1..0>\NAC"26;
%"GND"
"1","(-6350,1000)","0","pure_quanta_power","I16";
;
CDS_LIB"pure_quanta_power"
SIZE"1B"
HDL_POWER"GND";
"A<SIZE-1..0>\NAC"13;
%"Q_RES"
"1","(-7450,600)","0","pure_quanta","I20";
;
LOCATION"R4451"
$SEC"1"
CDS_SEC"1"
VALUE"33.2"
WATTAGE"1/16W"
MATERIAL"CHIP"
TOLERANCE"1%"
ROOM"USB3_HUB1_CYP"
PACK_TYPE"0402LF"
CDS_LIB"pure_quanta"
PART_NUMBER"CS03322FB03";
"B"
$PN"2"14;
"A"
$PN"1"50;
%"UNIVERSAL_POWER"
"1","(-6875,1150)","0","pure_quanta_power","I22";
;
HDL_POWER"P3V3_AUX"
CDS_LIB"pure_quanta_power"
BOM_COST"VR_SYSTEM";
"A"1;
%"Q_RES"
"2","(-5875,375)","0","pure_quanta","I23";
;
LOCATION"R4453"
$SEC"1"
CDS_SEC"1"
VALUE"47K"
TOLERANCE"0.1%"
WATTAGE"1/16W"
MATERIAL"EMPTY"
PACK_TYPE"0402LF"
ROOM"USB3_HUB1_CYP"
CDS_LIB"pure_quanta"
PART_NUMBER"CS34702BB05";
"A"
$PN"1"14;
"B"
$PN"2"25;
%"GND"
"1","(-5875,100)","0","pure_quanta_power","I24";
;
CDS_LIB"pure_quanta_power"
SIZE"1B"
HDL_POWER"GND";
"A<SIZE-1..0>\NAC"25;
%"Q_CAP"
"1","(-6350,425)","0","pure_quanta","I25";
;
LOCATION"C2317"
$SEC"1"
CDS_SEC"1"
TOLERANCE"10%"
VALUE"1UF"
PACK_TYPE"C0402"
MATERIAL"X6S"
VOLTAGE"25V"
ROOM"USB3_HUB1_CYP"
CDS_LIB"pure_quanta"
PART_NUMBER"CH5104KEB02";
"B"
$PN"2"25;
"A"
$PN"1"14;
%"P1V0_AUX"
"1","(-2475,6425)","0","pure_quanta_power","I26";
;
HDL_POWER"P5V_AUX"
BOM_COST"VR_SYSTEM "
CDS_LIB"pure_quanta_power";
"A"2;
%"Q_RES"
"1","(-2825,6125)","0","pure_quanta","I27";
;
LOCATION"R4450"
$SEC"1"
CDS_SEC"1"
TOLERANCE"5%"
PACK_TYPE"0402LF"
MATERIAL"CHIP"
WATTAGE"1/16W"
VALUE"0"
ROOM"USB3_HUB1_CYP"
CDS_LIB"pure_quanta"
PART_NUMBER"CS00002JB13";
"B"
$PN"2"2;
"A"
$PN"1"44;
%"Q_CAP"
"1","(-1525,6025)","0","pure_quanta","I28";
;
LOCATION"C6027"
$SEC"1"
CDS_SEC"1"
ROOM"USB3_HUB1_CYP"
VALUE"22UF"
VOLTAGE"16V"
TOLERANCE"20%"
MATERIAL"X6S"
PACK_TYPE"C0805"
CDS_LIB"pure_quanta"
PART_NUMBER"CH6223MEA00";
"B"
$PN"2"24;
"A"
$PN"1"23;
%"Q_CAP"
"1","(-1075,6000)","0","pure_quanta","I29";
;
LOCATION"C6028"
$SEC"1"
CDS_SEC"1"
ROOM"USB3_HUB1_CYP"
VALUE"470PF"
VOLTAGE"50V"
MATERIAL"X7R"
TOLERANCE"10%"
PACK_TYPE"0402"
CDS_LIB"pure_quanta"
PART_NUMBER"TMP_QCH14706KB18";
"B"
$PN"2"24;
"A"
$PN"1"23;
%"GND"
"1","(-975,5400)","0","pure_quanta_power","I30";
;
CDS_LIB"pure_quanta_power"
SIZE"1B"
HDL_POWER"GND";
"A<SIZE-1..0>\NAC"24;
%"P1V0_AUX"
"1","(-1525,6400)","0","pure_quanta_power","I31";
;
HDL_POWER"P5V_AUX"
CDS_LIB"pure_quanta_power"
BOM_COST"VR_SYSTEM ";
"A"23;
%"GND"
"1","(-3800,1075)","0","pure_quanta_power","I36";
;
SIZE"1B"
CDS_LIB"pure_quanta_power"
HDL_POWER"GND";
"A<SIZE-1..0>\NAC"16;
%"Q_RES"
"1","(-7000,4225)","0","pure_quanta","I37";
;
LOCATION"R6202"
$SEC"1"
CDS_SEC"1"
TOLERANCE"1%"
VALUE"200"
MATERIAL"CHIP"
ROOM"USB3_HUB1_CYP"
WATTAGE"1/16W"
PACK_TYPE"0402LF"
CDS_LIB"pure_quanta"
PART_NUMBER"CS12002FB06";
"B"
$PN"2"47;
"A"
$PN"1"22;
%"Q_RES"
"1","(-7025,4125)","0","pure_quanta","I39";
;
LOCATION"R6203"
$SEC"1"
CDS_SEC"1"
MATERIAL"CHIP"
VALUE"6.04K"
ROOM"USB3_HUB1_CYP"
TOLERANCE"1%"
PACK_TYPE"0402LF"
WATTAGE"1/16W"
CDS_LIB"pure_quanta"
PART_NUMBER"CS26042FB04";
"B"
$PN"2"46;
"A"
$PN"1"22;
%"GND"
"1","(-7725,4000)","0","pure_quanta_power","I40";
;
SIZE"1B"
CDS_LIB"pure_quanta_power"
HDL_POWER"GND";
"A<SIZE-1..0>\NAC"22;
%"Q_RES"
"2","(-7175,3275)","0","pure_quanta","I41";
;
LOCATION"R6204"
$SEC"1"
CDS_SEC"1"
ROOM"USB3_HUB1_CYP"
WATTAGE"1/16W"
MATERIAL"CHIP"
TOLERANCE"1%"
VALUE"10K"
PACK_TYPE"0402LF"
CDS_LIB"pure_quanta"
PART_NUMBER"CS31002FB08";
"A"
$PN"1"21;
"B"
$PN"2"39;
%"UNIVERSAL_POWER"
"1","(-7650,3775)","0","pure_quanta_power","I42";
;
HDL_POWER"P3V3_AUX"
CDS_LIB"pure_quanta_power"
BOM_COST"VR_SYSTEM";
"A"21;
%"Q_RES"
"2","(-7475,3275)","0","pure_quanta","I43";
;
LOCATION"R6205"
$SEC"1"
CDS_SEC"1"
TOLERANCE"1%"
WATTAGE"1/16W"
MATERIAL"CHIP"
PACK_TYPE"0402LF"
ROOM"USB3_HUB1_CYP"
VALUE"10K"
CDS_LIB"pure_quanta"
PART_NUMBER"CS31002FB08";
"A"
$PN"1"21;
"B"
$PN"2"40;
%"Q_RES"
"2","(-7775,3275)","0","pure_quanta","I44";
;
LOCATION"R6206"
$SEC"1"
CDS_SEC"1"
PACK_TYPE"0402LF"
MATERIAL"CHIP"
TOLERANCE"1%"
VALUE"10K"
ROOM"USB3_HUB1_CYP"
WATTAGE"1/16W"
CDS_LIB"pure_quanta"
PART_NUMBER"CS31002FB08";
"A"
$PN"1"21;
"B"
$PN"2"10;
%"Q_RES"
"2","(-8100,3275)","0","pure_quanta","I45";
;
LOCATION"R6207"
$SEC"1"
CDS_SEC"1"
MATERIAL"CHIP"
WATTAGE"1/16W"
TOLERANCE"1%"
VALUE"10K"
PACK_TYPE"0402LF"
ROOM"USB3_HUB1_CYP"
CDS_LIB"pure_quanta"
PART_NUMBER"CS31002FB08";
"A"
$PN"1"21;
"B"
$PN"2"41;
%"P1V0_AUX"
"1","(-7025,6525)","0","pure_quanta_power","I46";
;
HDL_POWER"P5V_AUX"
CDS_LIB"pure_quanta_power"
BOM_COST"VR_SYSTEM ";
"A"3;
%"Q_RES"
"2","(-7025,6300)","0","pure_quanta","I47";
;
LOCATION"R6208"
$SEC"1"
CDS_SEC"1"
MATERIAL"CHIP"
WATTAGE"1/16W"
PACK_TYPE"0402LF"
TOLERANCE"1%"
VALUE"10K"
ROOM"USB3_HUB1_CYP"
CDS_LIB"pure_quanta"
PART_NUMBER"CS31002FB08";
"A"
$PN"1"3;
"B"
$PN"2"57;
%"Q_RES"
"2","(-7025,5800)","0","pure_quanta","I48";
;
LOCATION"R6209"
$SEC"1"
CDS_SEC"1"
WATTAGE"1/16W"
TOLERANCE"1%"
PACK_TYPE"0402LF"
VALUE"10K"
ROOM"USB3_HUB1_CYP"
MATERIAL"CHIP"
CDS_LIB"pure_quanta"
PART_NUMBER"CS31002FB08";
"A"
$PN"1"57;
"B"
$PN"2"4;
%"GND"
"1","(-7025,5375)","0","pure_quanta_power","I49";
;
CDS_LIB"pure_quanta_power"
SIZE"1B"
HDL_POWER"GND";
"A<SIZE-1..0>\NAC"4;
%"GND"
"1","(-3300,500)","0","pure_quanta_power","I61";
;
CDS_LIB"pure_quanta_power"
SIZE"1B"
HDL_POWER"GND";
"A<SIZE-1..0>\NAC"5;
%"GND"
"1","(-2850,475)","0","pure_quanta_power","I62";
;
SIZE"1B"
CDS_LIB"pure_quanta_power"
HDL_POWER"GND";
"A<SIZE-1..0>\NAC"6;
%"UNIVERSAL_POWER"
"1","(-3100,1525)","0","pure_quanta_power","I63";
;
HDL_POWER"P3V3_AUX"
CDS_LIB"pure_quanta_power"
BOM_COST"VR_SYSTEM";
"A"17;
%"M24128BWMN6TP"
"1","(-2050,2825)","0","pure_quanta","I64";
;
LOCATION"U6003"
SEC"1"
VALUE"M24128-BWMN6TP"
ROOM"USB3_HUB1_CYP"
PART_TYPE"SMLF"
MATERIAL"IC"
CDS_LIB"pure_quanta"
NEEDS_NO_SIZE"TRUE"
CDS_LMAN_SYM_OUTLINE"-150,125,150,-125"
SEC_TYPE""
PART_NUMBER"AKE30Z00613";
"E0"
$PN"1"37;
"E1"
$PN"2"36;
"E2"
$PN"3"35;
"VSS"
$PN"4"7;
"SDA"
$PN"5"32;
"SCL"
$PN"6"33;
"WC# \B"
$PN"7"34;
"VCC"
$PN"8"18;
%"Q_RES"
"2","(-1050,3225)","2","pure_quanta","I65";
;
LOCATION"R6222"
$SEC"1"
CDS_SEC"1"
MATERIAL"CHIP"
WATTAGE"1/16W"
TOLERANCE"1%"
ROOM"USB3_HUB1_CYP"
VALUE"10K"
PACK_TYPE"0402LF"
CDS_LIB"pure_quanta"
PART_NUMBER"CS31002FB08";
"A"
$PN"1"19;
"B"
$PN"2"37;
%"Q_RES"
"2","(-850,2375)","0","pure_quanta","I66";
;
LOCATION"R6219"
$SEC"1"
CDS_SEC"1"
PACK_TYPE"0402LF"
MATERIAL"CHIP"
WATTAGE"1/16W"
TOLERANCE"1%"
VALUE"10K"
ROOM"USB3_HUB1_CYP"
CDS_LIB"pure_quanta"
PART_NUMBER"CS31002FB08";
"A"
$PN"1"36;
"B"
$PN"2"20;
%"Q_RES"
"2","(-450,2375)","0","pure_quanta","I67";
;
LOCATION"R6221"
$SEC"1"
CDS_SEC"1"
PACK_TYPE"0402LF"
TOLERANCE"1%"
MATERIAL"CHIP"
WATTAGE"1/16W"
VALUE"10K"
ROOM"USB3_HUB1_CYP"
CDS_LIB"pure_quanta"
PART_NUMBER"CS31002FB08";
"A"
$PN"1"35;
"B"
$PN"2"20;
%"Q_RES"
"2","(-1050,2400)","2","pure_quanta","I68";
;
LOCATION"R6217"
$SEC"1"
CDS_SEC"1"
ROOM"USB3_HUB1_CYP"
VALUE"10K"
WATTAGE"1/16W"
PACK_TYPE"0402LF"
TOLERANCE"1%"
MATERIAL"EMPTY"
CDS_LIB"pure_quanta"
PART_NUMBER"CS31002FB08";
"A"
$PN"1"37;
"B"
$PN"2"20;
%"Q_RES"
"2","(-850,3200)","0","pure_quanta","I69";
;
LOCATION"R6218"
$SEC"1"
CDS_SEC"1"
ROOM"USB3_HUB1_CYP"
TOLERANCE"1%"
WATTAGE"1/16W"
MATERIAL"EMPTY"
VALUE"10K"
PACK_TYPE"0402LF"
CDS_LIB"pure_quanta"
PART_NUMBER"CS31002FB08";
"A"
$PN"1"19;
"B"
$PN"2"36;
%"Q_RES"
"2","(-450,3200)","0","pure_quanta","I70";
;
LOCATION"R6220"
$SEC"1"
CDS_SEC"1"
TOLERANCE"1%"
VALUE"10K"
PACK_TYPE"0402LF"
MATERIAL"EMPTY"
WATTAGE"1/16W"
ROOM"USB3_HUB1_CYP"
CDS_LIB"pure_quanta"
PART_NUMBER"CS31002FB08";
"A"
$PN"1"19;
"B"
$PN"2"35;
%"GND"
"1","(-1050,1925)","0","pure_quanta_power","I71";
;
CDS_LIB"pure_quanta_power"
SIZE"1B"
HDL_POWER"GND";
"A<SIZE-1..0>\NAC"20;
%"UNIVERSAL_POWER"
"1","(-1050,3775)","0","pure_quanta_power","I72";
;
HDL_POWER"P3V3_AUX"
BOM_COST"VR_SYSTEM"
CDS_LIB"pure_quanta_power";
"A"19;
%"GND"
"1","(-1550,2625)","0","pure_quanta_power","I73";
;
SIZE"1B"
CDS_LIB"pure_quanta_power"
HDL_POWER"GND";
"A<SIZE-1..0>\NAC"7;
%"UNIVERSAL_POWER"
"1","(-2425,3575)","0","pure_quanta_power","I74";
;
HDL_POWER"P3V3_AUX"
BOM_COST"VR_SYSTEM"
CDS_LIB"pure_quanta_power";
"A"18;
%"Q_CAP"
"1","(-2650,3325)","0","pure_quanta","I75";
;
LOCATION"C6083"
$SEC"1"
CDS_SEC"1"
ROOM"USB3_HUB1_CYP"
VALUE"0.1UF"
VOLTAGE"25V"
TOLERANCE"10%"
MATERIAL"X7R"
PACK_TYPE"0402"
CDS_LIB"pure_quanta"
PART_NUMBER"CH4104K1B00";
"B"
$PN"2"8;
"A"
$PN"1"18;
%"GND"
"1","(-2650,3075)","0","pure_quanta_power","I76";
;
CDS_LIB"pure_quanta_power"
SIZE"1B"
HDL_POWER"GND";
"A<SIZE-1..0>\NAC"8;
%"Q_RES"
"2","(-2700,2425)","2","pure_quanta","I77";
;
LOCATION"R6223"
$SEC"1"
CDS_SEC"1"
PACK_TYPE"0402LF"
ROOM"USB3_HUB1_CYP"
VALUE"1K"
TOLERANCE"1%"
WATTAGE"1/16W"
MATERIAL"CHIP"
BOM_COST"VR_SYSTEM "
REUSE_ID"3"
CDS_LIB"pure_quanta"
PART_NUMBER"CS21002FB06";
"A"
$PN"1"34;
"B"
$PN"2"9;
%"GND"
"1","(-2700,2125)","0","pure_quanta_power","I78";
;
CDS_LIB"pure_quanta_power"
SIZE"1B"
HDL_POWER"GND";
"A<SIZE-1..0>\NAC"9;
%"Q_RES"
"1","(-3200,2750)","0","pure_quanta","I83";
;
LOCATION"R6225"
$SEC"1"
CDS_SEC"1"
ROOM"USB3_HUB1_CYP"
MATERIAL"EMPTY"
VALUE"33.2"
TOLERANCE"1%"
CDS_LIB"pure_quanta"
WATTAGE"1/16W"
PACK_TYPE"0402LF"
PART_NUMBER"CS03322FB03";
"B"
$PN"2"32;
"A"
$PN"1"11;
%"Q_RES"
"1","(-3200,2800)","0","pure_quanta","I84";
;
LOCATION"R6224"
$SEC"1"
CDS_SEC"1"
TOLERANCE"1%"
ROOM"USB3_HUB1_CYP"
MATERIAL"EMPTY"
VALUE"33.2"
WATTAGE"1/16W"
PACK_TYPE"0402LF"
CDS_LIB"pure_quanta"
PART_NUMBER"CS03322FB03";
"B"
$PN"2"33;
"A"
$PN"1"38;
%"Q_RES"
"2","(-2900,3300)","0","pure_quanta","I85";
;
LOCATION"R6226"
SEC"1"
PACK_TYPE"0402LF"
ROOM"USB3_HUB1_CYP"
WATTAGE"1/16W"
MATERIAL"EMPTY"
TOLERANCE"1%"
VALUE"10K"
SEC_TYPE"0402LF"
CDS_LIB"pure_quanta"
PART_NUMBER"CS31002FB08";
"A"
$PN"1"18;
"B"
$PN"2"33;
%"Q_RES"
"2","(-2975,3300)","2","pure_quanta","I86";
;
LOCATION"R6227"
SEC"1"
VALUE"10K"
TOLERANCE"1%"
WATTAGE"1/16W"
MATERIAL"EMPTY"
ROOM"USB3_HUB1_CYP"
PACK_TYPE"0402LF"
CDS_LIB"pure_quanta"
SEC_TYPE"0402LF"
PART_NUMBER"CS31002FB08";
"A"
$PN"1"18;
"B"
$PN"2"32;
%"Q_RES"
"2","(-3300,1125)","0","pure_quanta","I87";
;
LOCATION"R6213"
$SEC"1"
CDS_SEC"1"
PACK_TYPE"0402LF"
MATERIAL"CHIP"
VALUE"10K"
TOLERANCE"1%"
WATTAGE"1/16W"
ROOM"USB3_HUB1_CYP"
CDS_LIB"pure_quanta"
PART_NUMBER"CS31002FB08";
"A"
$PN"1"17;
"B"
$PN"2"27;
%"Q_RES"
"2","(-3300,750)","0","pure_quanta","I88";
;
LOCATION"R6214"
$SEC"1"
CDS_SEC"1"
ROOM"USB3_HUB1_CYP"
WATTAGE"1/16W"
MATERIAL"EMPTY"
VALUE"10K"
PACK_TYPE"0402LF"
TOLERANCE"1%"
CDS_LIB"pure_quanta"
PART_NUMBER"CS31002FB08";
"A"
$PN"1"27;
"B"
$PN"2"5;
%"Q_RES"
"2","(-2850,1125)","0","pure_quanta","I89";
;
LOCATION"R6215"
$SEC"1"
CDS_SEC"1"
TOLERANCE"1%"
WATTAGE"1/16W"
PACK_TYPE"0402LF"
MATERIAL"CHIP"
VALUE"10K"
ROOM"USB3_HUB1_CYP"
CDS_LIB"pure_quanta"
PART_NUMBER"CS31002FB08";
"A"
$PN"1"17;
"B"
$PN"2"15;
%"Q_RES"
"2","(-2850,725)","0","pure_quanta","I90";
;
LOCATION"R6216"
$SEC"1"
CDS_SEC"1"
ROOM"USB3_HUB1_CYP"
VALUE"10K"
MATERIAL"EMPTY"
PACK_TYPE"0402LF"
WATTAGE"1/16W"
TOLERANCE"1%"
CDS_LIB"pure_quanta"
PART_NUMBER"CS31002FB08";
"A"
$PN"1"15;
"B"
$PN"2"6;
%"Q_CAP"
"1","(-8000,1550)","0","pure_quanta","I91";
;
LOCATION"C93"
$SEC"1"
CDS_SEC"1"
VOLTAGE"50V"
MATERIAL"C0G"
TOLERANCE"5%"
PACK_TYPE"0402"
VALUE"15PF"
ROOM"USB3_HUB1_CYP"
CDS_LIB"pure_quanta"
PART_NUMBER"CH01506JB06";
"B"
$PN"2"26;
"A"
$PN"1"45;
%"Q_CAP"
"1","(-6350,1500)","0","pure_quanta","I92";
;
LOCATION"C91"
$SEC"1"
CDS_SEC"1"
TOLERANCE"5%"
MATERIAL"C0G"
VOLTAGE"50V"
VALUE"12PF"
ROOM"USB3_HUB1_CYP"
PACK_TYPE"C0402"
CDS_LIB"pure_quanta"
PART_NUMBER"CH01206JB05";
"B"
$PN"2"13;
"A"
$PN"1"12;
%"Q_RES"
"2","(-6875,850)","0","pure_quanta","I93";
;
LOCATION"R4452"
$SEC"1"
CDS_SEC"1"
PACK_TYPE"0402LF"
TOLERANCE"1%"
VALUE"10K"
MATERIAL"EMPTY"
WATTAGE"1/16W"
ROOM"USB3_HUB1_CYP"
CDS_LIB"pure_quanta"
PART_NUMBER"CS31002FB08";
"A"
$PN"1"1;
"B"
$PN"2"14;
END.
